# HONEY BADGER PTB(D)HS-1A BOM of 55.B0714.D02G_20150213.xlsx — HONEY BADGER PTB(D)HS-1A BOM of (bom)
| Level | Parent Number | Part Number | Description | Green Factor | Life Cycle State | Manufacturer | Manufacturer Part Number | Source | BOM Usage | M/P Code | S/D | Qty | UoM | Location |
| 1 | 55.B0714.D02G | 022.40008.0011 | SW PUSH BUTTON 3P MS-B1PL-10 DIP ,PA66 | R2_SA; | Released | WELLBUYING | MS-B1PL-10 | Single |  | Purchase | DIP | 1 | PCS | SW1 |
| 1 | 55.B0714.D02G | 20.81942.024 | CONN CTR 4P+20S RT 51939-689LF ,PA66 | R2_SA; | Released | FCI | 51939-689LF | Single |  | Purchase | DIP | 1 | PCS | CN4 |
| 1 | 55.B0714.D02G | 55.B0714.S02G | HONEY BADGER PTB (S) HS-1A | N/A; | Released |  |  |  | E | Manufacture | DIP | 1 | PCS |  |
| 2 | 55.B0714.S02G | 48.64W24.01A | PCB 14629-1A HONEY BADGER PTB CARD 4L HA | R2_C; | Released | HANNSTAR |  | Single |  | Purchase | SMT | 1 | PCS |  |
| 2 | 55.B0714.S02G | 63.00000.00L | CHIP RES 0 J 1/10W 0603 | R2_SA;HF_SA;G_SA; | Released | TA-I ; RALEC ; YAGEO ; WALSIN | RM06JTN0 ; RTT03000JTP ; RC0603JR-070RL ; WR06X000PTL | Multiple |  | Purchase | SMT | 1 | PCS | PR65 |
| 2 | 55.B0714.S02G | 63.68031.16L | CHIP RES 68 J 1/8W 0805 | R2_SA;HF_SA;G_SA; | Released | RALEC ; TA-I ; YAGEO | RTT05680JTP ; RM10JTN680 ; RC0805JR-0768RL | Multiple |  | Purchase | SMT | 1 | PCS | R378 |
| 2 | 55.B0714.S02G | 63.R0034.1DL | CHIP RES 0 J 1/16W 0402 | R2_SA;HF_SA;G_SA; | Released | TA-I;RALEC;CYNTEC;YAGEO;WALSIN | RM04JTN0;RTT02000JTH;RR0510X-000-XN;RC0402JR-070RL;WR04X000PTL | Multiple |  | Purchase | SMT | 12 | PCS | R366 R384 R385 R386 R387 R388 R389 R390 R391 R480 R481 R482 |
| 2 | 55.B0714.S02G | 64.10005.6DL | CHIP RES 100 F 1/16W 0402 | R2_SA;HF_SA;G_SA; | Released | TA-I ; RALEC ; CYNTEC ; YAGEO;WALSIN | RM04FTN1000 ; RTT021000FTH ; RR0510S-1000-FN ; RC0402FR-07100RL;WR04X1000FTL | Multiple |  | Purchase | SMT | 1 | PCS | R375 |
| 2 | 55.B0714.S02G | 64.10025.6DL | CHIP RES 10K F 1/16W 0402 | R2_SA;HF_SA;G_SA; | Released | TA-I;RALEC;CYNTEC;YAGEO;WALSIN | RM04FTN1002 ; RTT021002FTH ; RR0510S-103-FN ; RC0402FR-0710KL;WR04X1002FTL | Multiple |  | Purchase | SMT | 5 | PCS | R342 R343 R344 R353 R379 |
| 2 | 55.B0714.S02G | 64.10035.6DL | CHIP RES 100K F 1/16W 0402 | R2_SA;HF_SA;G_SA; | Released | TA-I;RALEC;CYNTEC;YAGEO;WALSIN | RM04FTN1003 ; RTT021003FTH ; RR0510S-104-FN ; RC0402FR-07100KL;WR04X1003FTL | Multiple |  | Purchase | SMT | 1 | PCS | R376 |
| 2 | 55.B0714.S02G | 64.20015.55L | CHIP RES 2K F 1/10W 0603 | R2_SA;HF_SA;G_SA; | Released | TA-I ; RALEC ; YAGEO;WALSIN | RM06FTN2001 ; RTT032001FTP ; RC0603FR-072KL;WR06X2001FTL | Multiple |  | Purchase | SMT | 1 | PCS | R483 |
| 2 | 55.B0714.S02G | 64.47035.6DL | CHIP RES 470K F 1/16W 0402 | R2_SA;HF_SA;G_SA; | Released | TA-I;RALEC;CYNTEC;YAGEO;WALSIN | RM04FTN4703;RTT024703FTH;RR0510S-474-FN;RC0402FR-07470KL;WR04X4703FTL | Multiple |  | Purchase | SMT | 1 | PCS | R374 |
| 2 | 55.B0714.S02G | 71.P9511.00W | IC BUF PCA9511ADP-T TSSOP 8P | R2_SA; | Released | NXP | PCA9511ADP-T | Single |  | Purchase | SMT | 1 | PCS | U51 |
| 2 | 55.B0714.S02G | 75.00325.010 | XTOR PHOTO SFH325-3 SMD BJ | R2_SA; | Released | OSRAM | SFH325-3 | Single |  | Purchase | SMT | 1 | PCS | Q31 |
| 2 | 55.B0714.S02G | 75.00426.010 | LED IR EMITT SFH426 SMD | R2_SA; | Released | OSRAM | SFH426 | Single |  | Purchase | SMT | 1 | PCS | LED16 |
| 2 | 55.B0714.S02G | 77.26861.05L | CHIP CAP POS 68U 16V M7343 ESR | R2_SA; | Released | SANYO | 16TQC68MY | Single |  | Purchase | SMT | 3 | PCS | TC3 TC4 TC5 |
| 2 | 55.B0714.S02G | 78.10324.2FL | CHIP CAP C 0.01U 50V K0402 X7R | R2_SA;HF_SA;G_SA; | Released | MURATA;PHYCOMP;DARFON;TDK;SAMSUNG;WALSIN;MURATA | GRM155R71H103KA88D;223858715636;C1005X7R103KGT;C1005X7R1H103KT;CL05B103KB5NNNC;0402B103K500CT;WBM155R71H103KA01D | Multiple |  | Purchase | SMT | 1 | PCS | C345 |
| 2 | 55.B0714.S02G | 78.10424.2BL | CHIP CAP C 0.1U 50V K0603 X7R | R2_SA;HF_SA;G_SA; | Released | MURATA;TDK;AVX;PHYCOMP;SAMSUNG;DARFON;MATSUKI;WALSIN | GRM188R71H104KA93D;C1608X7R1H104KT000N;06035C104KAT2A;223858615649;CL10B104KB8NNNC;C1608X7R104KGT;MAG03X7R1H104K;0603B104K500CT | Multiple |  | Purchase | SMT | 1 | PCS | C344 |
| 2 | 55.B0714.S02G | 78.10622.51L | CHIP CAP C 10U 25V K0805 X5R | R2_SA;HF_SA;G_SA; | Released | MATSUKI;SAMSUNG;TAIYO;AVX;MURATA;TDK;YAGEO | MAG05X5R1E106K;CL21A106KAYNNNE;TMK212BJ106KG-TD;CM21X5R106K25AT;GRM21BR61E106KA73L;C2012X5R1E106KT;CC0805KKX5R8BB106 | Multiple |  | Purchase | SMT | 3 | PCS | C348 C349 C355 |
| 2 | 55.B0714.S02G | 83.00191.K70 | LED GREEN LTST-C191KGKT-5A SMD | R2_SA;HF_SA; | Released | LITEON | LTST-C191KGKT-5A | Single |  | Purchase | SMT | 1 | PCS | LED1 |
| 2 | 55.B0714.S02G | 84.02222.V11 | XTOR MMBT2222A NPN SOT-23 | R2_SA;HF_SA;G_SA; | Released | PANJIT | MMBT2222A | Single |  | Purchase | SMT | 1 | PCS | Q33 |
| 2 | 55.B0714.S02G | 84.27002.W31 | FET MOS 2N7002 NC SOT-23 | R2_SA;HF_SA;G_SA; | Released | PANJIT | 2N7002 | Single |  | Purchase | SMT | 1 | PCS | Q34 |
| 1 | 55.B0714.D02G | 60.B0729.001 | ASSY PTB MAYLAR HB | R2_C; | Released | TBD |  | Single | M | Purchase | DIP | 1 | PCS |  |
| 1 | 55.B0714.D02G | 86.00Q43.140 | SCRW NUT HEX M3 | R_SA;G_SA; | Released | TBD |  | Single |  | Purchase | DIP | 2 | PCS |  |
| 1 | 55.B0714.D02G | 86.1A524.100 | SCRW MACH PAN M3*10L | R_SA; | Released | TBD |  | Single |  | Purchase | DIP | 2 | PCS |  |
